(kicad_pcb
	(version 20260206)
	(generator "pcbnew")
	(generator_version "10.0")
	(general
		(thickness 1.6)
		(legacy_teardrops no)
	)
	(paper "A4")
	(title_block
		(title "03242023_DA0F0TMBIJ0_F0T_Motherboard_J_brd_V01_OCP.brd")
		(comment 1 "Grand Teton / footprints 1851-1858 of 6105")
	)
	(layers
		(0 "F.Cu" signal "TOP")
		(4 "In1.Cu" signal "GND")
		(6 "In2.Cu" signal "IN1")
		(8 "In3.Cu" signal "GND1")
		(10 "In4.Cu" signal "IN2")
		(12 "In5.Cu" signal "GND2")
		(14 "In6.Cu" signal "IN3")
		(16 "In7.Cu" signal "GND3")
		(18 "In8.Cu" signal "VCC")
		(20 "In9.Cu" signal "VCC1")
		(22 "In10.Cu" signal "GND4")
		(24 "In11.Cu" signal "IN4")
		(26 "In12.Cu" signal "GND5")
		(28 "In13.Cu" signal "IN5")
		(30 "In14.Cu" signal "GND6")
		(32 "In15.Cu" signal "IN6")
		(34 "In16.Cu" signal "GND7")
		(2 "B.Cu" signal "BOTTOM")
		(9 "F.Adhes" user "F.Adhesive")
		(11 "B.Adhes" user "B.Adhesive")
		(13 "F.Paste" user "Package Geometry/Pastemask Top")
		(15 "B.Paste" user "Package Geometry/Pastemask Bottom")
		(5 "F.SilkS" user "Ref Des/Silkscreen Top")
		(7 "B.SilkS" user "Ref Des/Silkscreen Bottom")
		(1 "F.Mask" user "Board Geometry/Soldermask Top")
		(3 "B.Mask" user "Board Geometry/Soldermask Bottom")
		(17 "Dwgs.User" user "User.Drawings")
		(19 "Cmts.User" user "User.Comments")
		(21 "Eco1.User" user "User.Eco1")
		(23 "Eco2.User" user "User.Eco2")
		(25 "Edge.Cuts" user "Board Geometry/Outline")
		(27 "Margin" user)
		(31 "F.CrtYd" user "Package Geometry/Place Bound Top")
		(29 "B.CrtYd" user "Package Geometry/Place Bound Bottom")
		(35 "F.Fab" user "Ref Des/Assembly Top")
		(33 "B.Fab" user "Ref Des/Assembly Bottom")
	)
	(footprint ""
		(layer "F.Cu")
		(at 449.973954 -118.336822 180)
		(property "Reference" "R1126"
			(at 0 0 180)
			(layer "F.SilkS")
			(hide yes)
			(effects
				(font
					(size 1.27 1.27)
				)
			)
		)
		(property "Value" ""
			(at 0 0 180)
			(layer "F.Fab")
			(effects
				(font
					(size 1.27 1.27)
				)
			)
		)
		(duplicate_pad_numbers_are_jumpers no)
		(fp_line
			(start 0.7874 0.4064)
			(end -0.7874 0.4064)
			(stroke
				(width 0.1524)
				(type default)
			)
			(layer "F.SilkS")
		)
		(fp_line
			(start 0.7874 -0.4064)
			(end 0.7874 0.4064)
			(stroke
				(width 0.1524)
				(type default)
			)
			(layer "F.SilkS")
		)
		(fp_line
			(start -0.7874 0.4064)
			(end -0.7874 -0.4064)
			(stroke
				(width 0.1524)
				(type default)
			)
			(layer "F.SilkS")
		)
		(fp_line
			(start -0.7874 -0.4064)
			(end 0.7874 -0.4064)
			(stroke
				(width 0.1524)
				(type default)
			)
			(layer "F.SilkS")
		)
		(fp_line
			(start 0.67945 0.3048)
			(end 0.120396 0.3048)
			(stroke
				(width 0.1)
				(type default)
			)
			(layer "F.Fab")
		)
		(fp_line
			(start 0.67945 -0.3048)
			(end 0.67945 0.3048)
			(stroke
				(width 0.1)
				(type default)
			)
			(layer "F.Fab")
		)
		(fp_line
			(start 0.12065 -0.2794)
			(end 0.12065 -0.3048)
			(stroke
				(width 0.1)
				(type default)
			)
			(layer "F.Fab")
		)
		(fp_line
			(start 0.12065 -0.3048)
			(end 0.67945 -0.3048)
			(stroke
				(width 0.1)
				(type default)
			)
			(layer "F.Fab")
		)
		(fp_line
			(start 0.120396 0.3048)
			(end 0.120396 0.2794)
			(stroke
				(width 0.1)
				(type default)
			)
			(layer "F.Fab")
		)
		(fp_line
			(start 0.120396 0.2794)
			(end -0.12065 0.2794)
			(stroke
				(width 0.1)
				(type default)
			)
			(layer "F.Fab")
		)
		(fp_line
			(start -0.12065 0.3048)
			(end -0.67945 0.3048)
			(stroke
				(width 0.1)
				(type default)
			)
			(layer "F.Fab")
		)
		(fp_line
			(start -0.12065 0.2794)
			(end -0.12065 0.3048)
			(stroke
				(width 0.1)
				(type default)
			)
			(layer "F.Fab")
		)
		(fp_line
			(start -0.12065 -0.2794)
			(end 0.12065 -0.2794)
			(stroke
				(width 0.1)
				(type default)
			)
			(layer "F.Fab")
		)
		(fp_line
			(start -0.12065 -0.305054)
			(end -0.12065 -0.2794)
			(stroke
				(width 0.1)
				(type default)
			)
			(layer "F.Fab")
		)
		(fp_line
			(start -0.67945 0.3048)
			(end -0.67945 -0.305054)
			(stroke
				(width 0.1)
				(type default)
			)
			(layer "F.Fab")
		)
		(fp_line
			(start -0.67945 -0.305054)
			(end -0.12065 -0.305054)
			(stroke
				(width 0.1)
				(type default)
			)
			(layer "F.Fab")
		)
		(pad "1" smd circle
			(at -0.40005 0 180)
			(size 0 0)
			(layers "F.Cu" "F.Mask" "F.Paste")
			(net "PD_SMB_OCP1_HP_ADD1")
		)
		(pad "2" smd circle
			(at 0.40005 0 180)
			(size 0 0)
			(layers "F.Cu" "F.Mask" "F.Paste")
			(net "GND")
		)
	)
	(footprint ""
		(layer "F.Cu")
		(at 193.3956 -125.336808 180)
		(property "Reference" "R4086"
			(at 0 0 180)
			(layer "F.SilkS")
			(hide yes)
			(effects
				(font
					(size 1.27 1.27)
				)
			)
		)
		(property "Value" ""
			(at 0 0 180)
			(layer "F.Fab")
			(effects
				(font
					(size 1.27 1.27)
				)
			)
		)
		(duplicate_pad_numbers_are_jumpers no)
		(fp_line
			(start 0.7874 0.4064)
			(end -0.7874 0.4064)
			(stroke
				(width 0.1524)
				(type default)
			)
			(layer "F.SilkS")
		)
		(fp_line
			(start 0.7874 -0.4064)
			(end 0.7874 0.4064)
			(stroke
				(width 0.1524)
				(type default)
			)
			(layer "F.SilkS")
		)
		(fp_line
			(start -0.7874 0.4064)
			(end -0.7874 -0.4064)
			(stroke
				(width 0.1524)
				(type default)
			)
			(layer "F.SilkS")
		)
		(fp_line
			(start -0.7874 -0.4064)
			(end 0.7874 -0.4064)
			(stroke
				(width 0.1524)
				(type default)
			)
			(layer "F.SilkS")
		)
		(fp_line
			(start 0.67945 0.3048)
			(end 0.120396 0.3048)
			(stroke
				(width 0.1)
				(type default)
			)
			(layer "F.Fab")
		)
		(fp_line
			(start 0.67945 -0.3048)
			(end 0.67945 0.3048)
			(stroke
				(width 0.1)
				(type default)
			)
			(layer "F.Fab")
		)
		(fp_line
			(start 0.12065 -0.2794)
			(end 0.12065 -0.3048)
			(stroke
				(width 0.1)
				(type default)
			)
			(layer "F.Fab")
		)
		(fp_line
			(start 0.12065 -0.3048)
			(end 0.67945 -0.3048)
			(stroke
				(width 0.1)
				(type default)
			)
			(layer "F.Fab")
		)
		(fp_line
			(start 0.120396 0.3048)
			(end 0.120396 0.2794)
			(stroke
				(width 0.1)
				(type default)
			)
			(layer "F.Fab")
		)
		(fp_line
			(start 0.120396 0.2794)
			(end -0.12065 0.2794)
			(stroke
				(width 0.1)
				(type default)
			)
			(layer "F.Fab")
		)
		(fp_line
			(start -0.12065 0.3048)
			(end -0.67945 0.3048)
			(stroke
				(width 0.1)
				(type default)
			)
			(layer "F.Fab")
		)
		(fp_line
			(start -0.12065 0.2794)
			(end -0.12065 0.3048)
			(stroke
				(width 0.1)
				(type default)
			)
			(layer "F.Fab")
		)
		(fp_line
			(start -0.12065 -0.2794)
			(end 0.12065 -0.2794)
			(stroke
				(width 0.1)
				(type default)
			)
			(layer "F.Fab")
		)
		(fp_line
			(start -0.12065 -0.305054)
			(end -0.12065 -0.2794)
			(stroke
				(width 0.1)
				(type default)
			)
			(layer "F.Fab")
		)
		(fp_line
			(start -0.67945 0.3048)
			(end -0.67945 -0.305054)
			(stroke
				(width 0.1)
				(type default)
			)
			(layer "F.Fab")
		)
		(fp_line
			(start -0.67945 -0.305054)
			(end -0.12065 -0.305054)
			(stroke
				(width 0.1)
				(type default)
			)
			(layer "F.Fab")
		)
		(pad "1" smd circle
			(at -0.40005 0 180)
			(size 0 0)
			(layers "F.Cu" "F.Mask" "F.Paste")
			(net "P3V3_AUX_FPGA_VCCIO2")
		)
		(pad "2" smd circle
			(at 0.40005 0 180)
			(size 0 0)
			(layers "F.Cu" "F.Mask" "F.Paste")
			(net "PULL_FPGA_PB46A")
		)
	)
	(footprint ""
		(layer "F.Cu")
		(at 22.723094 -168.181274 90)
		(property "Reference" "R2557"
			(at 0 0 90)
			(layer "F.SilkS")
			(hide yes)
			(effects
				(font
					(size 1.27 1.27)
				)
			)
		)
		(property "Value" ""
			(at 0 0 90)
			(layer "F.Fab")
			(effects
				(font
					(size 1.27 1.27)
				)
			)
		)
		(duplicate_pad_numbers_are_jumpers no)
		(fp_line
			(start 0.7874 -0.4064)
			(end 0.7874 0.4064)
			(stroke
				(width 0.1524)
				(type default)
			)
			(layer "F.SilkS")
		)
		(fp_line
			(start -0.7874 -0.4064)
			(end 0.7874 -0.4064)
			(stroke
				(width 0.1524)
				(type default)
			)
			(layer "F.SilkS")
		)
		(fp_line
			(start 0.7874 0.4064)
			(end -0.7874 0.4064)
			(stroke
				(width 0.1524)
				(type default)
			)
			(layer "F.SilkS")
		)
		(fp_line
			(start -0.7874 0.4064)
			(end -0.7874 -0.4064)
			(stroke
				(width 0.1524)
				(type default)
			)
			(layer "F.SilkS")
		)
		(fp_line
			(start -0.12065 -0.305054)
			(end -0.12065 -0.2794)
			(stroke
				(width 0.1)
				(type default)
			)
			(layer "F.Fab")
		)
		(fp_line
			(start -0.67945 -0.305054)
			(end -0.12065 -0.305054)
			(stroke
				(width 0.1)
				(type default)
			)
			(layer "F.Fab")
		)
		(fp_line
			(start 0.67945 -0.3048)
			(end 0.67945 0.3048)
			(stroke
				(width 0.1)
				(type default)
			)
			(layer "F.Fab")
		)
		(fp_line
			(start 0.12065 -0.3048)
			(end 0.67945 -0.3048)
			(stroke
				(width 0.1)
				(type default)
			)
			(layer "F.Fab")
		)
		(fp_line
			(start 0.12065 -0.2794)
			(end 0.12065 -0.3048)
			(stroke
				(width 0.1)
				(type default)
			)
			(layer "F.Fab")
		)
		(fp_line
			(start -0.12065 -0.2794)
			(end 0.12065 -0.2794)
			(stroke
				(width 0.1)
				(type default)
			)
			(layer "F.Fab")
		)
		(fp_line
			(start 0.120396 0.2794)
			(end -0.12065 0.2794)
			(stroke
				(width 0.1)
				(type default)
			)
			(layer "F.Fab")
		)
		(fp_line
			(start -0.12065 0.2794)
			(end -0.12065 0.3048)
			(stroke
				(width 0.1)
				(type default)
			)
			(layer "F.Fab")
		)
		(fp_line
			(start 0.67945 0.3048)
			(end 0.120396 0.3048)
			(stroke
				(width 0.1)
				(type default)
			)
			(layer "F.Fab")
		)
		(fp_line
			(start 0.120396 0.3048)
			(end 0.120396 0.2794)
			(stroke
				(width 0.1)
				(type default)
			)
			(layer "F.Fab")
		)
		(fp_line
			(start -0.12065 0.3048)
			(end -0.67945 0.3048)
			(stroke
				(width 0.1)
				(type default)
			)
			(layer "F.Fab")
		)
		(fp_line
			(start -0.67945 0.3048)
			(end -0.67945 -0.305054)
			(stroke
				(width 0.1)
				(type default)
			)
			(layer "F.Fab")
		)
		(pad "1" smd circle
			(at -0.40005 0 90)
			(size 0 0)
			(layers "F.Cu" "F.Mask" "F.Paste")
			(net "IRQ_PVCCD_CPU1_VRHOT_LVC3_R_N")
		)
		(pad "2" smd circle
			(at 0.40005 0 90)
			(size 0 0)
			(layers "F.Cu" "F.Mask" "F.Paste")
			(net "IRQ_PVCCD_CPU1_VRHOT_LVC3_N")
		)
	)
	(footprint ""
		(layer "F.Cu")
		(at 177.156364 -337.483958)
		(property "Reference" "PC1204"
			(at 0 0 0)
			(layer "F.SilkS")
			(hide yes)
			(effects
				(font
					(size 1.27 1.27)
				)
			)
		)
		(property "Value" ""
			(at 0 0 0)
			(layer "F.Fab")
			(effects
				(font
					(size 1.27 1.27)
				)
			)
		)
		(duplicate_pad_numbers_are_jumpers no)
		(fp_line
			(start 2.750058 0.999998)
			(end -2.750058 0.999998)
			(stroke
				(width 0.1524)
				(type default)
			)
			(layer "F.SilkS")
		)
		(fp_circle
			(center 0 0.999998)
			(end 2.750058 0.999998)
			(stroke
				(width 0.1524)
				(type default)
			)
			(fill no)
			(layer "F.SilkS")
		)
		(fp_poly
			(pts
				(arc
					(start 2.750058 0.999998)
					(mid 0 3.750056)
					(end -2.750058 0.999998)
				)
			)
			(stroke
				(width 0)
				(type default)
			)
			(fill yes)
			(layer "F.SilkS")
		)
		(fp_circle
			(center 0 0.999998)
			(end 2.750058 0.999998)
			(stroke
				(width 0.1)
				(type default)
			)
			(fill no)
			(layer "F.Fab")
		)
		(pad "1" thru_hole rect
			(at 0 0)
			(size 1.5748 1.5748)
			(drill 1.0668)
			(layers "*.Cu" "*.Mask")
			(remove_unused_layers no)
			(net "PVCCFA_EHV_FIVRA_CPU1")
			(clearance 0)
			(padstack
				(mode front_inner_back)
				(layer "Inner"
					(shape circle)
					(size 1.5748 1.5748)
					(clearance 0)
				)
				(layer "B.Cu"
					(shape rect)
					(size 1.5748 1.5748)
					(clearance 0)
				)
			)
		)
		(pad "2" thru_hole circle
			(at 0 1.999996)
			(size 1.5748 1.5748)
			(drill 1.0668)
			(layers "*.Cu" "*.Mask")
			(remove_unused_layers no)
			(net "GND")
			(clearance 0)
		)
	)
	(footprint ""
		(layer "F.Cu")
		(at 150.57247 -92.291916)
		(property "Reference" "R4392"
			(at 0 0 0)
			(layer "F.SilkS")
			(hide yes)
			(effects
				(font
					(size 1.27 1.27)
				)
			)
		)
		(property "Value" ""
			(at 0 0 0)
			(layer "F.Fab")
			(effects
				(font
					(size 1.27 1.27)
				)
			)
		)
		(duplicate_pad_numbers_are_jumpers no)
		(fp_line
			(start -0.7874 -0.4064)
			(end 0.7874 -0.4064)
			(stroke
				(width 0.1524)
				(type default)
			)
			(layer "F.SilkS")
		)
		(fp_line
			(start -0.7874 0.4064)
			(end -0.7874 -0.4064)
			(stroke
				(width 0.1524)
				(type default)
			)
			(layer "F.SilkS")
		)
		(fp_line
			(start 0.7874 -0.4064)
			(end 0.7874 0.4064)
			(stroke
				(width 0.1524)
				(type default)
			)
			(layer "F.SilkS")
		)
		(fp_line
			(start 0.7874 0.4064)
			(end -0.7874 0.4064)
			(stroke
				(width 0.1524)
				(type default)
			)
			(layer "F.SilkS")
		)
		(fp_line
			(start -0.67945 -0.305054)
			(end -0.12065 -0.305054)
			(stroke
				(width 0.1)
				(type default)
			)
			(layer "F.Fab")
		)
		(fp_line
			(start -0.67945 0.3048)
			(end -0.67945 -0.305054)
			(stroke
				(width 0.1)
				(type default)
			)
			(layer "F.Fab")
		)
		(fp_line
			(start -0.12065 -0.305054)
			(end -0.12065 -0.2794)
			(stroke
				(width 0.1)
				(type default)
			)
			(layer "F.Fab")
		)
		(fp_line
			(start -0.12065 -0.2794)
			(end 0.12065 -0.2794)
			(stroke
				(width 0.1)
				(type default)
			)
			(layer "F.Fab")
		)
		(fp_line
			(start -0.12065 0.2794)
			(end -0.12065 0.3048)
			(stroke
				(width 0.1)
				(type default)
			)
			(layer "F.Fab")
		)
		(fp_line
			(start -0.12065 0.3048)
			(end -0.67945 0.3048)
			(stroke
				(width 0.1)
				(type default)
			)
			(layer "F.Fab")
		)
		(fp_line
			(start 0.120396 0.2794)
			(end -0.12065 0.2794)
			(stroke
				(width 0.1)
				(type default)
			)
			(layer "F.Fab")
		)
		(fp_line
			(start 0.120396 0.3048)
			(end 0.120396 0.2794)
			(stroke
				(width 0.1)
				(type default)
			)
			(layer "F.Fab")
		)
		(fp_line
			(start 0.12065 -0.3048)
			(end 0.67945 -0.3048)
			(stroke
				(width 0.1)
				(type default)
			)
			(layer "F.Fab")
		)
		(fp_line
			(start 0.12065 -0.2794)
			(end 0.12065 -0.3048)
			(stroke
				(width 0.1)
				(type default)
			)
			(layer "F.Fab")
		)
		(fp_line
			(start 0.67945 -0.3048)
			(end 0.67945 0.3048)
			(stroke
				(width 0.1)
				(type default)
			)
			(layer "F.Fab")
		)
		(fp_line
			(start 0.67945 0.3048)
			(end 0.120396 0.3048)
			(stroke
				(width 0.1)
				(type default)
			)
			(layer "F.Fab")
		)
		(pad "1" smd circle
			(at -0.40005 0)
			(size 0 0)
			(layers "F.Cu" "F.Mask" "F.Paste")
			(net "H_CPU_ERR0_LVC2_R_N")
		)
		(pad "2" smd circle
			(at 0.40005 0)
			(size 0 0)
			(layers "F.Cu" "F.Mask" "F.Paste")
			(net "H_CPU_ERR0_PCH_R_N")
		)
	)
	(footprint ""
		(layer "F.Cu")
		(at 55.87873 -16.099536 90)
		(property "Reference" "C834"
			(at 0 0 90)
			(layer "F.SilkS")
			(hide yes)
			(effects
				(font
					(size 1.27 1.27)
				)
			)
		)
		(property "Value" ""
			(at 0 0 90)
			(layer "F.Fab")
			(effects
				(font
					(size 1.27 1.27)
				)
			)
		)
		(duplicate_pad_numbers_are_jumpers no)
		(fp_line
			(start 0.299974 -0.150114)
			(end 0.299974 0.150114)
			(stroke
				(width 0.1)
				(type default)
			)
			(layer "F.Fab")
		)
		(fp_line
			(start -0.299974 -0.150114)
			(end 0.299974 -0.150114)
			(stroke
				(width 0.1)
				(type default)
			)
			(layer "F.Fab")
		)
		(fp_line
			(start 0.299974 0.150114)
			(end -0.299974 0.150114)
			(stroke
				(width 0.1)
				(type default)
			)
			(layer "F.Fab")
		)
		(fp_line
			(start -0.299974 0.150114)
			(end -0.299974 -0.150114)
			(stroke
				(width 0.1)
				(type default)
			)
			(layer "F.Fab")
		)
		(pad "1" smd rect
			(at -0.2667 0 90)
			(size 0.3048 0.381)
			(layers "F.Cu" "F.Mask" "F.Paste")
			(net "P5E_CPU1_PE1_TX_C_DN<1>")
		)
		(pad "2" smd rect
			(at 0.2667 0 90)
			(size 0.3048 0.381)
			(layers "F.Cu" "F.Mask" "F.Paste")
			(net "P5E_CPU1_PE1_TX_DN<1>")
		)
	)
	(footprint ""
		(layer "F.Cu")
		(at 430.386236 -16.088614 90)
		(property "Reference" "C866"
			(at 0 0 90)
			(layer "F.SilkS")
			(hide yes)
			(effects
				(font
					(size 1.27 1.27)
				)
			)
		)
		(property "Value" ""
			(at 0 0 90)
			(layer "F.Fab")
			(effects
				(font
					(size 1.27 1.27)
				)
			)
		)
		(duplicate_pad_numbers_are_jumpers no)
		(fp_line
			(start 0.299974 -0.150114)
			(end 0.299974 0.150114)
			(stroke
				(width 0.1)
				(type default)
			)
			(layer "F.Fab")
		)
		(fp_line
			(start -0.299974 -0.150114)
			(end 0.299974 -0.150114)
			(stroke
				(width 0.1)
				(type default)
			)
			(layer "F.Fab")
		)
		(fp_line
			(start 0.299974 0.150114)
			(end -0.299974 0.150114)
			(stroke
				(width 0.1)
				(type default)
			)
			(layer "F.Fab")
		)
		(fp_line
			(start -0.299974 0.150114)
			(end -0.299974 -0.150114)
			(stroke
				(width 0.1)
				(type default)
			)
			(layer "F.Fab")
		)
		(pad "1" smd rect
			(at -0.2667 0 90)
			(size 0.3048 0.381)
			(layers "F.Cu" "F.Mask" "F.Paste")
			(net "P5E_CPU0_PE1_TX_C_DN<1>")
		)
		(pad "2" smd rect
			(at 0.2667 0 90)
			(size 0.3048 0.381)
			(layers "F.Cu" "F.Mask" "F.Paste")
			(net "P5E_CPU0_PE1_TX_DN<1>")
		)
	)
	(footprint ""
		(layer "F.Cu")
		(at 127.288544 -74.853292 -90)
		(property "Reference" "C1322"
			(at 0 0 270)
			(layer "F.SilkS")
			(hide yes)
			(effects
				(font
					(size 1.27 1.27)
				)
			)
		)
		(property "Value" ""
			(at 0 0 270)
			(layer "F.Fab")
			(effects
				(font
					(size 1.27 1.27)
				)
			)
		)
		(duplicate_pad_numbers_are_jumpers no)
		(fp_line
			(start -0.7874 0.4064)
			(end -0.7874 -0.4064)
			(stroke
				(width 0.1524)
				(type default)
			)
			(layer "F.SilkS")
		)
		(fp_line
			(start 0.7874 0.4064)
			(end -0.7874 0.4064)
			(stroke
				(width 0.1524)
				(type default)
			)
			(layer "F.SilkS")
		)
		(fp_line
			(start -0.7874 -0.4064)
			(end 0.7874 -0.4064)
			(stroke
				(width 0.1524)
				(type default)
			)
			(layer "F.SilkS")
		)
		(fp_line
			(start 0.7874 -0.4064)
			(end 0.7874 0.4064)
			(stroke
				(width 0.1524)
				(type default)
			)
			(layer "F.SilkS")
		)
		(fp_line
			(start -0.67945 0.3048)
			(end -0.67945 -0.305054)
			(stroke
				(width 0.1)
				(type default)
			)
			(layer "F.Fab")
		)
		(fp_line
			(start -0.12065 0.3048)
			(end -0.67945 0.3048)
			(stroke
				(width 0.1)
				(type default)
			)
			(layer "F.Fab")
		)
		(fp_line
			(start 0.120396 0.3048)
			(end 0.120396 0.2794)
			(stroke
				(width 0.1)
				(type default)
			)
			(layer "F.Fab")
		)
		(fp_line
			(start 0.67945 0.3048)
			(end 0.120396 0.3048)
			(stroke
				(width 0.1)
				(type default)
			)
			(layer "F.Fab")
		)
		(fp_line
			(start -0.12065 0.2794)
			(end -0.12065 0.3048)
			(stroke
				(width 0.1)
				(type default)
			)
			(layer "F.Fab")
		)
		(fp_line
			(start 0.120396 0.2794)
			(end -0.12065 0.2794)
			(stroke
				(width 0.1)
				(type default)
			)
			(layer "F.Fab")
		)
		(fp_line
			(start -0.12065 -0.2794)
			(end 0.12065 -0.2794)
			(stroke
				(width 0.1)
				(type default)
			)
			(layer "F.Fab")
		)
		(fp_line
			(start 0.12065 -0.2794)
			(end 0.12065 -0.3048)
			(stroke
				(width 0.1)
				(type default)
			)
			(layer "F.Fab")
		)
		(fp_line
			(start 0.12065 -0.3048)
			(end 0.67945 -0.3048)
			(stroke
				(width 0.1)
				(type default)
			)
			(layer "F.Fab")
		)
		(fp_line
			(start 0.67945 -0.3048)
			(end 0.67945 0.3048)
			(stroke
				(width 0.1)
				(type default)
			)
			(layer "F.Fab")
		)
		(fp_line
			(start -0.67945 -0.305054)
			(end -0.12065 -0.305054)
			(stroke
				(width 0.1)
				(type default)
			)
			(layer "F.Fab")
		)
		(fp_line
			(start -0.12065 -0.305054)
			(end -0.12065 -0.2794)
			(stroke
				(width 0.1)
				(type default)
			)
			(layer "F.Fab")
		)
		(pad "1" smd circle
			(at -0.40005 0 270)
			(size 0 0)
			(layers "F.Cu" "F.Mask" "F.Paste")
			(net "P3V3_AUX")
		)
		(pad "2" smd circle
			(at 0.40005 0 270)
			(size 0 0)
			(layers "F.Cu" "F.Mask" "F.Paste")
			(net "GND")
		)
	)
)
